(kicad_pcb
	(version 20260206)
	(generator "pcbnew")
	(generator_version "10.0")
	(general
		(thickness 1.6)
		(legacy_teardrops no)
	)
	(paper "A4")
	(title_block
		(title "01162023_DA0F0TEBIF0_F0T_Expander_BD_F_brd_V02_OCP.brd")
		(comment 1 "Grand Teton / footprints 4350-4356 of 9728")
	)
	(layers
		(0 "F.Cu" signal "TOP")
		(4 "In1.Cu" signal "GND")
		(6 "In2.Cu" signal "VCC")
		(8 "In3.Cu" signal "VCC1")
		(10 "In4.Cu" signal "GND1")
		(12 "In5.Cu" signal "IN1")
		(14 "In6.Cu" signal "GND2")
		(16 "In7.Cu" signal "IN2")
		(18 "In8.Cu" signal "GND3")
		(20 "In9.Cu" signal "IN3")
		(22 "In10.Cu" signal "GND4")
		(24 "In11.Cu" signal "IN4")
		(26 "In12.Cu" signal "GND5")
		(28 "In13.Cu" signal "IN5")
		(30 "In14.Cu" signal "GND6")
		(32 "In15.Cu" signal "IN6")
		(34 "In16.Cu" signal "GND7")
		(2 "B.Cu" signal "BOTTOM")
		(9 "F.Adhes" user "F.Adhesive")
		(11 "B.Adhes" user "B.Adhesive")
		(13 "F.Paste" user "Package Geometry/Pastemask Top")
		(15 "B.Paste" user "Package Geometry/Pastemask Bottom")
		(5 "F.SilkS" user "Ref Des/Silkscreen Top")
		(7 "B.SilkS" user "Ref Des/Silkscreen Bottom")
		(1 "F.Mask" user "Board Geometry/Soldermask Top")
		(3 "B.Mask" user "Board Geometry/Soldermask Bottom")
		(17 "Dwgs.User" user "User.Drawings")
		(19 "Cmts.User" user "User.Comments")
		(21 "Eco1.User" user "User.Eco1")
		(23 "Eco2.User" user "User.Eco2")
		(25 "Edge.Cuts" user "Board Geometry/Outline")
		(27 "Margin" user)
		(31 "F.CrtYd" user "Package Geometry/Place Bound Top")
		(29 "B.CrtYd" user "Package Geometry/Place Bound Bottom")
		(35 "F.Fab" user "Ref Des/Assembly Top")
		(33 "B.Fab" user "Ref Des/Assembly Bottom")
	)
	(footprint ""
		(layer "F.Cu")
		(at 381.254 -207.518)
		(property "Reference" "R4632"
			(at 0 0 0)
			(layer "F.SilkS")
			(hide yes)
			(effects
				(font
					(size 1.27 1.27)
				)
			)
		)
		(property "Value" ""
			(at 0 0 0)
			(layer "F.Fab")
			(effects
				(font
					(size 1.27 1.27)
				)
			)
		)
		(duplicate_pad_numbers_are_jumpers no)
		(fp_line
			(start -0.7874 -0.4064)
			(end 0.7874 -0.4064)
			(stroke
				(width 0.1524)
				(type default)
			)
			(layer "F.SilkS")
		)
		(fp_line
			(start -0.7874 0.4064)
			(end -0.7874 -0.4064)
			(stroke
				(width 0.1524)
				(type default)
			)
			(layer "F.SilkS")
		)
		(fp_line
			(start 0.7874 -0.4064)
			(end 0.7874 0.4064)
			(stroke
				(width 0.1524)
				(type default)
			)
			(layer "F.SilkS")
		)
		(fp_line
			(start 0.7874 0.4064)
			(end -0.7874 0.4064)
			(stroke
				(width 0.1524)
				(type default)
			)
			(layer "F.SilkS")
		)
		(fp_line
			(start -0.67945 -0.305054)
			(end -0.12065 -0.305054)
			(stroke
				(width 0.1)
				(type default)
			)
			(layer "F.Fab")
		)
		(fp_line
			(start -0.67945 0.3048)
			(end -0.67945 -0.305054)
			(stroke
				(width 0.1)
				(type default)
			)
			(layer "F.Fab")
		)
		(fp_line
			(start -0.12065 -0.305054)
			(end -0.12065 -0.2794)
			(stroke
				(width 0.1)
				(type default)
			)
			(layer "F.Fab")
		)
		(fp_line
			(start -0.12065 -0.2794)
			(end 0.12065 -0.2794)
			(stroke
				(width 0.1)
				(type default)
			)
			(layer "F.Fab")
		)
		(fp_line
			(start -0.12065 0.2794)
			(end -0.12065 0.3048)
			(stroke
				(width 0.1)
				(type default)
			)
			(layer "F.Fab")
		)
		(fp_line
			(start -0.12065 0.3048)
			(end -0.67945 0.3048)
			(stroke
				(width 0.1)
				(type default)
			)
			(layer "F.Fab")
		)
		(fp_line
			(start 0.120396 0.2794)
			(end -0.12065 0.2794)
			(stroke
				(width 0.1)
				(type default)
			)
			(layer "F.Fab")
		)
		(fp_line
			(start 0.120396 0.3048)
			(end 0.120396 0.2794)
			(stroke
				(width 0.1)
				(type default)
			)
			(layer "F.Fab")
		)
		(fp_line
			(start 0.12065 -0.3048)
			(end 0.67945 -0.3048)
			(stroke
				(width 0.1)
				(type default)
			)
			(layer "F.Fab")
		)
		(fp_line
			(start 0.12065 -0.2794)
			(end 0.12065 -0.3048)
			(stroke
				(width 0.1)
				(type default)
			)
			(layer "F.Fab")
		)
		(fp_line
			(start 0.67945 -0.3048)
			(end 0.67945 0.3048)
			(stroke
				(width 0.1)
				(type default)
			)
			(layer "F.Fab")
		)
		(fp_line
			(start 0.67945 0.3048)
			(end 0.120396 0.3048)
			(stroke
				(width 0.1)
				(type default)
			)
			(layer "F.Fab")
		)
		(pad "1" smd circle
			(at -0.40005 0)
			(size 0 0)
			(layers "F.Cu" "F.Mask" "F.Paste")
			(net "NIC0_PEX_PWR_EN")
		)
		(pad "2" smd circle
			(at 0.40005 0)
			(size 0 0)
			(layers "F.Cu" "F.Mask" "F.Paste")
			(net "NIC0_PEX_PWR_EN_R")
		)
	)
	(footprint ""
		(layer "F.Cu")
		(at 149.387814 -282.018232)
		(property "Reference" "C3241"
			(at 0 0 0)
			(layer "F.SilkS")
			(hide yes)
			(effects
				(font
					(size 1.27 1.27)
				)
			)
		)
		(property "Value" ""
			(at 0 0 0)
			(layer "F.Fab")
			(effects
				(font
					(size 1.27 1.27)
				)
			)
		)
		(duplicate_pad_numbers_are_jumpers no)
		(fp_line
			(start -1.2954 -0.5842)
			(end 1.2954 -0.5842)
			(stroke
				(width 0.1524)
				(type default)
			)
			(layer "F.SilkS")
		)
		(fp_line
			(start -1.2954 0.5842)
			(end -1.2954 -0.5842)
			(stroke
				(width 0.1524)
				(type default)
			)
			(layer "F.SilkS")
		)
		(fp_line
			(start 1.2954 -0.5842)
			(end 1.2954 0.5842)
			(stroke
				(width 0.1524)
				(type default)
			)
			(layer "F.SilkS")
		)
		(fp_line
			(start 1.2954 0.5842)
			(end -1.2954 0.5842)
			(stroke
				(width 0.1524)
				(type default)
			)
			(layer "F.SilkS")
		)
		(fp_line
			(start -1.1938 -0.4064)
			(end -0.8636 -0.4064)
			(stroke
				(width 0.1)
				(type default)
			)
			(layer "F.Fab")
		)
		(fp_line
			(start -1.1938 0.4064)
			(end -1.1938 -0.4064)
			(stroke
				(width 0.1)
				(type default)
			)
			(layer "F.Fab")
		)
		(fp_line
			(start -0.8636 -0.4572)
			(end 0.8636 -0.4572)
			(stroke
				(width 0.1)
				(type default)
			)
			(layer "F.Fab")
		)
		(fp_line
			(start -0.8636 -0.4064)
			(end -0.8636 -0.4572)
			(stroke
				(width 0.1)
				(type default)
			)
			(layer "F.Fab")
		)
		(fp_line
			(start -0.8636 0.4064)
			(end -1.1938 0.4064)
			(stroke
				(width 0.1)
				(type default)
			)
			(layer "F.Fab")
		)
		(fp_line
			(start -0.8636 0.4572)
			(end -0.8636 0.4064)
			(stroke
				(width 0.1)
				(type default)
			)
			(layer "F.Fab")
		)
		(fp_line
			(start 0.8636 -0.4572)
			(end 0.8636 -0.4064)
			(stroke
				(width 0.1)
				(type default)
			)
			(layer "F.Fab")
		)
		(fp_line
			(start 0.8636 -0.4064)
			(end 1.1938 -0.4064)
			(stroke
				(width 0.1)
				(type default)
			)
			(layer "F.Fab")
		)
		(fp_line
			(start 0.8636 0.4064)
			(end 0.8636 0.4572)
			(stroke
				(width 0.1)
				(type default)
			)
			(layer "F.Fab")
		)
		(fp_line
			(start 0.8636 0.4572)
			(end -0.8636 0.4572)
			(stroke
				(width 0.1)
				(type default)
			)
			(layer "F.Fab")
		)
		(fp_line
			(start 1.1938 -0.4064)
			(end 1.1938 0.4064)
			(stroke
				(width 0.1)
				(type default)
			)
			(layer "F.Fab")
		)
		(fp_line
			(start 1.1938 0.4064)
			(end 0.8636 0.4064)
			(stroke
				(width 0.1)
				(type default)
			)
			(layer "F.Fab")
		)
		(pad "1" smd rect
			(at -0.7366 0 270)
			(size 0.7112 0.8128)
			(layers "F.Cu" "F.Mask" "F.Paste")
			(net "SYSPLL_VDDA18_PEX1")
		)
		(pad "2" smd rect
			(at 0.7366 0 270)
			(size 0.7112 0.8128)
			(layers "F.Cu" "F.Mask" "F.Paste")
			(net "GND")
		)
	)
	(footprint ""
		(layer "F.Cu")
		(at 471.118184 -551.319192 180)
		(property "Reference" "SCREW_SSD8_1"
			(at -5.207 -1.402334 0)
			(unlocked yes)
			(layer "B.SilkS")
			(effects
				(font
					(size 0.7874 0.5842)
					(thickness 0.1524)
				)
				(justify mirror)
			)
		)
		(property "Value" ""
			(at 0 0 180)
			(layer "F.Fab")
			(effects
				(font
					(size 1.27 1.27)
				)
			)
		)
		(duplicate_pad_numbers_are_jumpers no)
		(pad "1" thru_hole circle
			(at 0 0 180)
			(size 0.4572 0.4572)
			(drill 0.2032)
			(layers "*.Cu" "*.Mask")
			(remove_unused_layers no)
			(net "Net_9128")
			(clearance 0.127)
			(thermal_gap 0.127)
			(padstack
				(mode front_inner_back)
				(layer "Inner"
					(shape circle)
					(size 0.4572 0.4572)
					(clearance 0.127)
				)
				(layer "B.Cu"
					(shape circle)
					(size 0.508 0.508)
					(clearance 0.1016)
				)
			)
		)
	)
	(footprint ""
		(layer "F.Cu")
		(at 2.989072 -387.038342 -90)
		(property "Reference" "R6747"
			(at 0 0 270)
			(layer "F.SilkS")
			(hide yes)
			(effects
				(font
					(size 1.27 1.27)
				)
			)
		)
		(property "Value" ""
			(at 0 0 270)
			(layer "F.Fab")
			(effects
				(font
					(size 1.27 1.27)
				)
			)
		)
		(duplicate_pad_numbers_are_jumpers no)
		(fp_line
			(start 0.7874 0.4064)
			(end -0.459486 0.4064)
			(stroke
				(width 0.1524)
				(type default)
			)
			(layer "F.SilkS")
		)
		(fp_line
			(start -0.43815 -0.4064)
			(end 0.7874 -0.4064)
			(stroke
				(width 0.1524)
				(type default)
			)
			(layer "F.SilkS")
		)
		(fp_line
			(start 0.7874 -0.4064)
			(end 0.7874 0.4064)
			(stroke
				(width 0.1524)
				(type default)
			)
			(layer "F.SilkS")
		)
		(fp_line
			(start -0.67945 0.3048)
			(end -0.67945 -0.305054)
			(stroke
				(width 0.1)
				(type default)
			)
			(layer "F.Fab")
		)
		(fp_line
			(start -0.12065 0.3048)
			(end -0.67945 0.3048)
			(stroke
				(width 0.1)
				(type default)
			)
			(layer "F.Fab")
		)
		(fp_line
			(start 0.120396 0.3048)
			(end 0.120396 0.2794)
			(stroke
				(width 0.1)
				(type default)
			)
			(layer "F.Fab")
		)
		(fp_line
			(start 0.67945 0.3048)
			(end 0.120396 0.3048)
			(stroke
				(width 0.1)
				(type default)
			)
			(layer "F.Fab")
		)
		(fp_line
			(start -0.12065 0.2794)
			(end -0.12065 0.3048)
			(stroke
				(width 0.1)
				(type default)
			)
			(layer "F.Fab")
		)
		(fp_line
			(start 0.120396 0.2794)
			(end -0.12065 0.2794)
			(stroke
				(width 0.1)
				(type default)
			)
			(layer "F.Fab")
		)
		(fp_line
			(start -0.12065 -0.2794)
			(end 0.12065 -0.2794)
			(stroke
				(width 0.1)
				(type default)
			)
			(layer "F.Fab")
		)
		(fp_line
			(start 0.12065 -0.2794)
			(end 0.12065 -0.3048)
			(stroke
				(width 0.1)
				(type default)
			)
			(layer "F.Fab")
		)
		(fp_line
			(start 0.12065 -0.3048)
			(end 0.67945 -0.3048)
			(stroke
				(width 0.1)
				(type default)
			)
			(layer "F.Fab")
		)
		(fp_line
			(start 0.67945 -0.3048)
			(end 0.67945 0.3048)
			(stroke
				(width 0.1)
				(type default)
			)
			(layer "F.Fab")
		)
		(fp_line
			(start -0.67945 -0.305054)
			(end -0.12065 -0.305054)
			(stroke
				(width 0.1)
				(type default)
			)
			(layer "F.Fab")
		)
		(fp_line
			(start -0.12065 -0.305054)
			(end -0.12065 -0.2794)
			(stroke
				(width 0.1)
				(type default)
			)
			(layer "F.Fab")
		)
		(pad "1" smd circle
			(at -0.40005 0 270)
			(size 0 0)
			(layers "F.Cu" "F.Mask" "F.Paste")
			(net "USB2_MB_BMC_USB8042_DN")
		)
		(pad "2" smd circle
			(at 0.40005 0 270)
			(size 0 0)
			(layers "F.Cu" "F.Mask" "F.Paste")
			(net "GND")
		)
	)
	(footprint ""
		(layer "F.Cu")
		(at 221.674944 -98.36912 -90)
		(property "Reference" "PC350"
			(at 0 0 270)
			(layer "F.SilkS")
			(hide yes)
			(effects
				(font
					(size 1.27 1.27)
				)
			)
		)
		(property "Value" ""
			(at 0 0 270)
			(layer "F.Fab")
			(effects
				(font
					(size 1.27 1.27)
				)
			)
		)
		(duplicate_pad_numbers_are_jumpers no)
		(fp_line
			(start -0.7874 0.4064)
			(end -0.7874 -0.4064)
			(stroke
				(width 0.1524)
				(type default)
			)
			(layer "F.SilkS")
		)
		(fp_line
			(start 0.7874 0.4064)
			(end -0.7874 0.4064)
			(stroke
				(width 0.1524)
				(type default)
			)
			(layer "F.SilkS")
		)
		(fp_line
			(start -0.7874 -0.4064)
			(end 0.7874 -0.4064)
			(stroke
				(width 0.1524)
				(type default)
			)
			(layer "F.SilkS")
		)
		(fp_line
			(start 0.7874 -0.4064)
			(end 0.7874 0.4064)
			(stroke
				(width 0.1524)
				(type default)
			)
			(layer "F.SilkS")
		)
		(fp_line
			(start -0.6858 0.3048)
			(end -0.6858 -0.3048)
			(stroke
				(width 0.1)
				(type default)
			)
			(layer "F.Fab")
		)
		(fp_line
			(start -0.1016 0.3048)
			(end -0.6858 0.3048)
			(stroke
				(width 0.1)
				(type default)
			)
			(layer "F.Fab")
		)
		(fp_line
			(start 0.1016 0.3048)
			(end 0.1016 0.2794)
			(stroke
				(width 0.1)
				(type default)
			)
			(layer "F.Fab")
		)
		(fp_line
			(start 0.6858 0.3048)
			(end 0.1016 0.3048)
			(stroke
				(width 0.1)
				(type default)
			)
			(layer "F.Fab")
		)
		(fp_line
			(start -0.1016 0.2794)
			(end -0.1016 0.3048)
			(stroke
				(width 0.1)
				(type default)
			)
			(layer "F.Fab")
		)
		(fp_line
			(start 0.1016 0.2794)
			(end -0.1016 0.2794)
			(stroke
				(width 0.1)
				(type default)
			)
			(layer "F.Fab")
		)
		(fp_line
			(start -0.1016 -0.2794)
			(end 0.1016 -0.2794)
			(stroke
				(width 0.1)
				(type default)
			)
			(layer "F.Fab")
		)
		(fp_line
			(start 0.1016 -0.2794)
			(end 0.1016 -0.3048)
			(stroke
				(width 0.1)
				(type default)
			)
			(layer "F.Fab")
		)
		(fp_line
			(start -0.6858 -0.3048)
			(end -0.1016 -0.3048)
			(stroke
				(width 0.1)
				(type default)
			)
			(layer "F.Fab")
		)
		(fp_line
			(start -0.1016 -0.3048)
			(end -0.1016 -0.2794)
			(stroke
				(width 0.1)
				(type default)
			)
			(layer "F.Fab")
		)
		(fp_line
			(start 0.1016 -0.3048)
			(end 0.6858 -0.3048)
			(stroke
				(width 0.1)
				(type default)
			)
			(layer "F.Fab")
		)
		(fp_line
			(start 0.6858 -0.3048)
			(end 0.6858 0.3048)
			(stroke
				(width 0.1)
				(type default)
			)
			(layer "F.Fab")
		)
		(pad "1" smd rect
			(at -0.40005 0 90)
			(size 0.4572 0.508)
			(layers "F.Cu" "F.Mask" "F.Paste")
			(net "P12V_NIC3_SS")
		)
		(pad "2" smd rect
			(at 0.40005 0 90)
			(size 0.4572 0.508)
			(layers "F.Cu" "F.Mask" "F.Paste")
			(net "GND")
		)
	)
	(footprint ""
		(layer "F.Cu")
		(at 428.319438 -150.70455 180)
		(property "Reference" "C640"
			(at 0 0 180)
			(layer "F.SilkS")
			(hide yes)
			(effects
				(font
					(size 1.27 1.27)
				)
			)
		)
		(property "Value" ""
			(at 0 0 180)
			(layer "F.Fab")
			(effects
				(font
					(size 1.27 1.27)
				)
			)
		)
		(duplicate_pad_numbers_are_jumpers no)
		(fp_line
			(start 0.299974 0.150114)
			(end -0.299974 0.150114)
			(stroke
				(width 0.1)
				(type default)
			)
			(layer "F.Fab")
		)
		(fp_line
			(start 0.299974 -0.150114)
			(end 0.299974 0.150114)
			(stroke
				(width 0.1)
				(type default)
			)
			(layer "F.Fab")
		)
		(fp_line
			(start -0.299974 0.150114)
			(end -0.299974 -0.150114)
			(stroke
				(width 0.1)
				(type default)
			)
			(layer "F.Fab")
		)
		(fp_line
			(start -0.299974 -0.150114)
			(end 0.299974 -0.150114)
			(stroke
				(width 0.1)
				(type default)
			)
			(layer "F.Fab")
		)
		(pad "1" smd rect
			(at -0.2667 0 180)
			(size 0.3048 0.381)
			(layers "F.Cu" "F.Mask" "F.Paste")
			(net "P5E_PEX3_STN0_TX_DN<12>")
		)
		(pad "2" smd rect
			(at 0.2667 0 180)
			(size 0.3048 0.381)
			(layers "F.Cu" "F.Mask" "F.Paste")
			(net "P5E_PEX3_STN0_TX_C_DN<12>")
		)
	)
	(footprint ""
		(layer "F.Cu")
		(at 150.394162 -239.726978 90)
		(property "Reference" "R6573"
			(at 0 0 90)
			(layer "F.SilkS")
			(hide yes)
			(effects
				(font
					(size 1.27 1.27)
				)
			)
		)
		(property "Value" ""
			(at 0 0 90)
			(layer "F.Fab")
			(effects
				(font
					(size 1.27 1.27)
				)
			)
		)
		(duplicate_pad_numbers_are_jumpers no)
		(fp_line
			(start 0.7874 -0.4064)
			(end 0.7874 0.4064)
			(stroke
				(width 0.1524)
				(type default)
			)
			(layer "F.SilkS")
		)
		(fp_line
			(start -0.7874 -0.4064)
			(end 0.7874 -0.4064)
			(stroke
				(width 0.1524)
				(type default)
			)
			(layer "F.SilkS")
		)
		(fp_line
			(start 0.7874 0.4064)
			(end -0.7874 0.4064)
			(stroke
				(width 0.1524)
				(type default)
			)
			(layer "F.SilkS")
		)
		(fp_line
			(start -0.7874 0.4064)
			(end -0.7874 -0.4064)
			(stroke
				(width 0.1524)
				(type default)
			)
			(layer "F.SilkS")
		)
		(fp_line
			(start -0.12065 -0.305054)
			(end -0.12065 -0.2794)
			(stroke
				(width 0.1)
				(type default)
			)
			(layer "F.Fab")
		)
		(fp_line
			(start -0.67945 -0.305054)
			(end -0.12065 -0.305054)
			(stroke
				(width 0.1)
				(type default)
			)
			(layer "F.Fab")
		)
		(fp_line
			(start 0.67945 -0.3048)
			(end 0.67945 0.3048)
			(stroke
				(width 0.1)
				(type default)
			)
			(layer "F.Fab")
		)
		(fp_line
			(start 0.12065 -0.3048)
			(end 0.67945 -0.3048)
			(stroke
				(width 0.1)
				(type default)
			)
			(layer "F.Fab")
		)
		(fp_line
			(start 0.12065 -0.2794)
			(end 0.12065 -0.3048)
			(stroke
				(width 0.1)
				(type default)
			)
			(layer "F.Fab")
		)
		(fp_line
			(start -0.12065 -0.2794)
			(end 0.12065 -0.2794)
			(stroke
				(width 0.1)
				(type default)
			)
			(layer "F.Fab")
		)
		(fp_line
			(start 0.120396 0.2794)
			(end -0.12065 0.2794)
			(stroke
				(width 0.1)
				(type default)
			)
			(layer "F.Fab")
		)
		(fp_line
			(start -0.12065 0.2794)
			(end -0.12065 0.3048)
			(stroke
				(width 0.1)
				(type default)
			)
			(layer "F.Fab")
		)
		(fp_line
			(start 0.67945 0.3048)
			(end 0.120396 0.3048)
			(stroke
				(width 0.1)
				(type default)
			)
			(layer "F.Fab")
		)
		(fp_line
			(start 0.120396 0.3048)
			(end 0.120396 0.2794)
			(stroke
				(width 0.1)
				(type default)
			)
			(layer "F.Fab")
		)
		(fp_line
			(start -0.12065 0.3048)
			(end -0.67945 0.3048)
			(stroke
				(width 0.1)
				(type default)
			)
			(layer "F.Fab")
		)
		(fp_line
			(start -0.67945 0.3048)
			(end -0.67945 -0.305054)
			(stroke
				(width 0.1)
				(type default)
			)
			(layer "F.Fab")
		)
		(pad "1" smd circle
			(at -0.40005 0 90)
			(size 0 0)
			(layers "F.Cu" "F.Mask" "F.Paste")
			(net "P1V8_PLL0_PEX1")
		)
		(pad "2" smd circle
			(at 0.40005 0 90)
			(size 0 0)
			(layers "F.Cu" "F.Mask" "F.Paste")
			(net "P1V8_PLL_PEX1_ADJ")
		)
	)
)
